(kicad_pcb
	(version 20260206)
	(generator "pcbnew")
	(generator_version "10.0")
	(general
		(thickness 1.6)
		(legacy_teardrops no)
	)
	(paper "A4")
	(title_block
		(title "01162023_DA0F0TEBIF0_F0T_Expander_BD_F_brd_V02_OCP.brd")
		(comment 1 "Grand Teton / footprint 5622 of 9728 (PEX2), pads 234-355 of 2397")
	)
	(layers
		(0 "F.Cu" signal "TOP")
		(4 "In1.Cu" signal "GND")
		(6 "In2.Cu" signal "VCC")
		(8 "In3.Cu" signal "VCC1")
		(10 "In4.Cu" signal "GND1")
		(12 "In5.Cu" signal "IN1")
		(14 "In6.Cu" signal "GND2")
		(16 "In7.Cu" signal "IN2")
		(18 "In8.Cu" signal "GND3")
		(20 "In9.Cu" signal "IN3")
		(22 "In10.Cu" signal "GND4")
		(24 "In11.Cu" signal "IN4")
		(26 "In12.Cu" signal "GND5")
		(28 "In13.Cu" signal "IN5")
		(30 "In14.Cu" signal "GND6")
		(32 "In15.Cu" signal "IN6")
		(34 "In16.Cu" signal "GND7")
		(2 "B.Cu" signal "BOTTOM")
		(9 "F.Adhes" user "F.Adhesive")
		(11 "B.Adhes" user "B.Adhesive")
		(13 "F.Paste" user "Package Geometry/Pastemask Top")
		(15 "B.Paste" user "Package Geometry/Pastemask Bottom")
		(5 "F.SilkS" user "Ref Des/Silkscreen Top")
		(7 "B.SilkS" user "Ref Des/Silkscreen Bottom")
		(1 "F.Mask" user "Board Geometry/Soldermask Top")
		(3 "B.Mask" user "Board Geometry/Soldermask Bottom")
		(17 "Dwgs.User" user "User.Drawings")
		(19 "Cmts.User" user "User.Comments")
		(21 "Eco1.User" user "User.Eco1")
		(23 "Eco2.User" user "User.Eco2")
		(25 "Edge.Cuts" user "Board Geometry/Outline")
		(27 "Margin" user)
		(31 "F.CrtYd" user "Package Geometry/Place Bound Top")
		(29 "B.CrtYd" user "Package Geometry/Place Bound Bottom")
		(35 "F.Fab" user "Ref Des/Assembly Top")
		(33 "B.Fab" user "Ref Des/Assembly Bottom")
	)
	(footprint ""
		(layer "F.Cu")
		(at 291.84981 -295.89984)
		(property "Reference" "PEX2"
			(at -3.35153 35.56762 0)
			(unlocked yes)
			(layer "F.SilkS")
			(effects
				(font
					(size 2.032 1.524)
					(thickness 0.1524)
				)
				(justify left)
			)
		)
		(property "Value" ""
			(at 0 0 0)
			(layer "F.Fab")
			(effects
				(font
					(size 1.27 1.27)
				)
			)
		)
		(duplicate_pad_numbers_are_jumpers no)
		(pad "AD40" smd circle
			(at 14.249908 -0.94996)
			(size 0.4572 0.4572)
			(layers "F.Cu" "F.Mask" "F.Paste")
			(net "GND")
		)
		(pad "AD41" smd circle
			(at 15.200122 -0.94996)
			(size 0.4572 0.4572)
			(layers "F.Cu" "F.Mask" "F.Paste")
			(net "Net_1657")
		)
		(pad "AD42" smd circle
			(at 16.150082 -0.94996)
			(size 0.4572 0.4572)
			(layers "F.Cu" "F.Mask" "F.Paste")
			(net "Net_1700")
		)
		(pad "AD43" smd circle
			(at 17.100042 -0.94996)
			(size 0.4572 0.4572)
			(layers "F.Cu" "F.Mask" "F.Paste")
			(net "GND")
		)
		(pad "AD44" smd circle
			(at 18.050002 -0.94996)
			(size 0.4572 0.4572)
			(layers "F.Cu" "F.Mask" "F.Paste")
			(net "GND")
		)
		(pad "AD45" smd circle
			(at 18.999962 -0.94996)
			(size 0.4572 0.4572)
			(layers "F.Cu" "F.Mask" "F.Paste")
			(net "GND")
		)
		(pad "AD46" smd circle
			(at 19.949922 -0.94996)
			(size 0.4572 0.4572)
			(layers "F.Cu" "F.Mask" "F.Paste")
			(net "GND")
		)
		(pad "AD47" smd circle
			(at 20.899882 -0.94996)
			(size 0.4572 0.4572)
			(layers "F.Cu" "F.Mask" "F.Paste")
			(net "GND")
		)
		(pad "AD48" smd circle
			(at 21.850096 -0.94996)
			(size 0.4572 0.4572)
			(layers "F.Cu" "F.Mask" "F.Paste")
			(net "Net_1650")
		)
		(pad "AD49" smd circle
			(at 22.800056 -0.94996)
			(size 0.4572 0.4572)
			(layers "F.Cu" "F.Mask" "F.Paste")
			(net "Net_1630")
		)
		(pad "AE1" smd circle
			(at -22.800056 0)
			(size 0.4572 0.4572)
			(layers "F.Cu" "F.Mask" "F.Paste")
			(net "CLK_100M_DB800ZL_PEX2_S3_R_DN")
		)
		(pad "AE2" smd circle
			(at -21.850096 0)
			(size 0.4572 0.4572)
			(layers "F.Cu" "F.Mask" "F.Paste")
			(net "CLK_100M_DB800ZL_PEX2_S3_R_DP")
		)
		(pad "AE3" smd circle
			(at -20.899882 0)
			(size 0.4572 0.4572)
			(layers "F.Cu" "F.Mask" "F.Paste")
			(net "GND")
		)
		(pad "AE4" smd circle
			(at -19.949922 0)
			(size 0.4572 0.4572)
			(layers "F.Cu" "F.Mask" "F.Paste")
			(net "GND")
		)
		(pad "AE5" smd circle
			(at -18.999962 0)
			(size 0.4572 0.4572)
			(layers "F.Cu" "F.Mask" "F.Paste")
			(net "GND")
		)
		(pad "AE6" smd circle
			(at -18.050002 0)
			(size 0.4572 0.4572)
			(layers "F.Cu" "F.Mask" "F.Paste")
			(net "GND")
		)
		(pad "AE7" smd circle
			(at -17.100042 0)
			(size 0.4572 0.4572)
			(layers "F.Cu" "F.Mask" "F.Paste")
			(net "Net_5394")
		)
		(pad "AE8" smd circle
			(at -16.150082 0)
			(size 0.4572 0.4572)
			(layers "F.Cu" "F.Mask" "F.Paste")
			(net "Net_5401")
		)
		(pad "AE9" smd circle
			(at -15.200122 0)
			(size 0.4572 0.4572)
			(layers "F.Cu" "F.Mask" "F.Paste")
			(net "GND")
		)
		(pad "AE10" smd circle
			(at -14.249908 0)
			(size 0.4572 0.4572)
			(layers "F.Cu" "F.Mask" "F.Paste")
			(net "P1V8_PEX")
		)
		(pad "AE11" smd circle
			(at -13.299948 0)
			(size 0.4572 0.4572)
			(layers "F.Cu" "F.Mask" "F.Paste")
			(net "GND")
		)
		(pad "AE12" smd circle
			(at -12.349988 0)
			(size 0.4572 0.4572)
			(layers "F.Cu" "F.Mask" "F.Paste")
			(net "GND")
		)
		(pad "AE13" smd circle
			(at -11.400028 0)
			(size 0.4572 0.4572)
			(layers "F.Cu" "F.Mask" "F.Paste")
			(net "PCEPLL3_VDDA18_PEX2")
		)
		(pad "AE14" smd circle
			(at -10.450068 0)
			(size 0.4572 0.4572)
			(layers "F.Cu" "F.Mask" "F.Paste")
			(net "GND")
		)
		(pad "AE15" smd circle
			(at -9.500108 0)
			(size 0.4572 0.4572)
			(layers "F.Cu" "F.Mask" "F.Paste")
			(net "P0V8_PEX2")
		)
		(pad "AE16" smd circle
			(at -8.549894 0)
			(size 0.4572 0.4572)
			(layers "F.Cu" "F.Mask" "F.Paste")
			(net "GND")
		)
		(pad "AE17" smd circle
			(at -7.599934 0)
			(size 0.4572 0.4572)
			(layers "F.Cu" "F.Mask" "F.Paste")
			(net "P0V8_PEX2")
		)
		(pad "AE18" smd circle
			(at -6.649974 0)
			(size 0.4572 0.4572)
			(layers "F.Cu" "F.Mask" "F.Paste")
			(net "GND")
		)
		(pad "AE19" smd circle
			(at -5.700014 0)
			(size 0.4572 0.4572)
			(layers "F.Cu" "F.Mask" "F.Paste")
			(net "P0V8_PEX2")
		)
		(pad "AE20" smd circle
			(at -4.750054 0)
			(size 0.4572 0.4572)
			(layers "F.Cu" "F.Mask" "F.Paste")
			(net "GND")
		)
		(pad "AE21" smd circle
			(at -3.800094 0)
			(size 0.4572 0.4572)
			(layers "F.Cu" "F.Mask" "F.Paste")
			(net "P0V8_PEX2")
		)
		(pad "AE22" smd circle
			(at -2.84988 0)
			(size 0.4572 0.4572)
			(layers "F.Cu" "F.Mask" "F.Paste")
			(net "GND")
		)
		(pad "AE23" smd circle
			(at -1.89992 0)
			(size 0.4572 0.4572)
			(layers "F.Cu" "F.Mask" "F.Paste")
			(net "P0V8_PEX2")
		)
		(pad "AE24" smd circle
			(at -0.94996 0)
			(size 0.4572 0.4572)
			(layers "F.Cu" "F.Mask" "F.Paste")
			(net "GND")
		)
		(pad "AE25" smd circle
			(at 0 0)
			(size 0.4572 0.4572)
			(layers "F.Cu" "F.Mask" "F.Paste")
			(net "P0V8_PEX2")
		)
		(pad "AE26" smd circle
			(at 0.94996 0)
			(size 0.4572 0.4572)
			(layers "F.Cu" "F.Mask" "F.Paste")
			(net "GND")
		)
		(pad "AE27" smd circle
			(at 1.89992 0)
			(size 0.4572 0.4572)
			(layers "F.Cu" "F.Mask" "F.Paste")
			(net "P0V8_PEX2")
		)
		(pad "AE28" smd circle
			(at 2.84988 0)
			(size 0.4572 0.4572)
			(layers "F.Cu" "F.Mask" "F.Paste")
			(net "GND")
		)
		(pad "AE29" smd circle
			(at 3.800094 0)
			(size 0.4572 0.4572)
			(layers "F.Cu" "F.Mask" "F.Paste")
			(net "P0V8_PEX2")
		)
		(pad "AE30" smd circle
			(at 4.750054 0)
			(size 0.4572 0.4572)
			(layers "F.Cu" "F.Mask" "F.Paste")
			(net "GND")
		)
		(pad "AE31" smd circle
			(at 5.700014 0)
			(size 0.4572 0.4572)
			(layers "F.Cu" "F.Mask" "F.Paste")
			(net "P0V8_PEX2")
		)
		(pad "AE32" smd circle
			(at 6.649974 0)
			(size 0.4572 0.4572)
			(layers "F.Cu" "F.Mask" "F.Paste")
			(net "GND")
		)
		(pad "AE33" smd circle
			(at 7.599934 0)
			(size 0.4572 0.4572)
			(layers "F.Cu" "F.Mask" "F.Paste")
			(net "P0V8_SERDES_VDDA_PEX2")
		)
		(pad "AE34" smd circle
			(at 8.549894 0)
			(size 0.4572 0.4572)
			(layers "F.Cu" "F.Mask" "F.Paste")
			(net "P0V8_SERDES_VDDA_PEX2")
		)
		(pad "AE35" smd circle
			(at 9.500108 0)
			(size 0.4572 0.4572)
			(layers "F.Cu" "F.Mask" "F.Paste")
			(net "GND")
		)
		(pad "AE36" smd circle
			(at 10.450068 0)
			(size 0.4572 0.4572)
			(layers "F.Cu" "F.Mask" "F.Paste")
			(net "P1V25_PEX2")
		)
		(pad "AE37" smd circle
			(at 11.400028 0)
			(size 0.4572 0.4572)
			(layers "F.Cu" "F.Mask" "F.Paste")
			(net "GND")
		)
		(pad "AE38" smd circle
			(at 12.349988 0)
			(size 0.4572 0.4572)
			(layers "F.Cu" "F.Mask" "F.Paste")
			(net "P1V25_SERDES_VDDPLL_PEX2")
		)
		(pad "AE39" smd circle
			(at 13.299948 0)
			(size 0.4572 0.4572)
			(layers "F.Cu" "F.Mask" "F.Paste")
			(net "GND")
		)
		(pad "AE40" smd circle
			(at 14.249908 0)
			(size 0.4572 0.4572)
			(layers "F.Cu" "F.Mask" "F.Paste")
			(net "GND")
		)
		(pad "AE41" smd circle
			(at 15.200122 0)
			(size 0.4572 0.4572)
			(layers "F.Cu" "F.Mask" "F.Paste")
			(net "GND")
		)
		(pad "AE42" smd circle
			(at 16.150082 0)
			(size 0.4572 0.4572)
			(layers "F.Cu" "F.Mask" "F.Paste")
			(net "GND")
		)
		(pad "AE43" smd circle
			(at 17.100042 0)
			(size 0.4572 0.4572)
			(layers "F.Cu" "F.Mask" "F.Paste")
			(net "Net_1689")
		)
		(pad "AE44" smd circle
			(at 18.050002 0)
			(size 0.4572 0.4572)
			(layers "F.Cu" "F.Mask" "F.Paste")
			(net "Net_1699")
		)
		(pad "AE45" smd circle
			(at 18.999962 0)
			(size 0.4572 0.4572)
			(layers "F.Cu" "F.Mask" "F.Paste")
			(net "GND")
		)
		(pad "AE46" smd circle
			(at 19.949922 0)
			(size 0.4572 0.4572)
			(layers "F.Cu" "F.Mask" "F.Paste")
			(net "Net_1538")
		)
		(pad "AE47" smd circle
			(at 20.899882 0)
			(size 0.4572 0.4572)
			(layers "F.Cu" "F.Mask" "F.Paste")
			(net "Net_1619")
		)
		(pad "AE48" smd circle
			(at 21.850096 0)
			(size 0.4572 0.4572)
			(layers "F.Cu" "F.Mask" "F.Paste")
			(net "GND")
		)
		(pad "AE49" smd circle
			(at 22.800056 0)
			(size 0.4572 0.4572)
			(layers "F.Cu" "F.Mask" "F.Paste")
			(net "GND")
		)
		(pad "AF1" smd circle
			(at -22.800056 0.94996)
			(size 0.4572 0.4572)
			(layers "F.Cu" "F.Mask" "F.Paste")
			(net "GND")
		)
		(pad "AF2" smd circle
			(at -21.850096 0.94996)
			(size 0.4572 0.4572)
			(layers "F.Cu" "F.Mask" "F.Paste")
			(net "GND")
		)
		(pad "AF3" smd circle
			(at -20.899882 0.94996)
			(size 0.4572 0.4572)
			(layers "F.Cu" "F.Mask" "F.Paste")
			(net "GND")
		)
		(pad "AF4" smd circle
			(at -19.949922 0.94996)
			(size 0.4572 0.4572)
			(layers "F.Cu" "F.Mask" "F.Paste")
			(net "Net_5313")
		)
		(pad "AF5" smd circle
			(at -18.999962 0.94996)
			(size 0.4572 0.4572)
			(layers "F.Cu" "F.Mask" "F.Paste")
			(net "Net_5314")
		)
		(pad "AF6" smd circle
			(at -18.050002 0.94996)
			(size 0.4572 0.4572)
			(layers "F.Cu" "F.Mask" "F.Paste")
			(net "GND")
		)
		(pad "AF7" smd circle
			(at -17.100042 0.94996)
			(size 0.4572 0.4572)
			(layers "F.Cu" "F.Mask" "F.Paste")
			(net "SPI_PEX2_SDIO0")
		)
		(pad "AF8" smd circle
			(at -16.150082 0.94996)
			(size 0.4572 0.4572)
			(layers "F.Cu" "F.Mask" "F.Paste")
			(net "SPI_PEX2_SDIO1")
		)
		(pad "AF9" smd circle
			(at -15.200122 0.94996)
			(size 0.4572 0.4572)
			(layers "F.Cu" "F.Mask" "F.Paste")
			(net "GND")
		)
		(pad "AF10" smd circle
			(at -14.249908 0.94996)
			(size 0.4572 0.4572)
			(layers "F.Cu" "F.Mask" "F.Paste")
			(net "P1V8_PEX")
		)
		(pad "AF11" smd circle
			(at -13.299948 0.94996)
			(size 0.4572 0.4572)
			(layers "F.Cu" "F.Mask" "F.Paste")
			(net "GND")
		)
		(pad "AF12" smd circle
			(at -12.349988 0.94996)
			(size 0.4572 0.4572)
			(layers "F.Cu" "F.Mask" "F.Paste")
			(net "PCEPLL4_VDDA18_PEX2")
		)
		(pad "AF13" smd circle
			(at -11.400028 0.94996)
			(size 0.4572 0.4572)
			(layers "F.Cu" "F.Mask" "F.Paste")
			(net "GND")
		)
		(pad "AF14" smd circle
			(at -10.450068 0.94996)
			(size 0.4572 0.4572)
			(layers "F.Cu" "F.Mask" "F.Paste")
			(net "P0V8_PEX2")
		)
		(pad "AF15" smd circle
			(at -9.500108 0.94996)
			(size 0.4572 0.4572)
			(layers "F.Cu" "F.Mask" "F.Paste")
			(net "GND")
		)
		(pad "AF16" smd circle
			(at -8.549894 0.94996)
			(size 0.4572 0.4572)
			(layers "F.Cu" "F.Mask" "F.Paste")
			(net "P0V8_PEX2")
		)
		(pad "AF17" smd circle
			(at -7.599934 0.94996)
			(size 0.4572 0.4572)
			(layers "F.Cu" "F.Mask" "F.Paste")
			(net "GND")
		)
		(pad "AF18" smd circle
			(at -6.649974 0.94996)
			(size 0.4572 0.4572)
			(layers "F.Cu" "F.Mask" "F.Paste")
			(net "P0V8_PEX2")
		)
		(pad "AF19" smd circle
			(at -5.700014 0.94996)
			(size 0.4572 0.4572)
			(layers "F.Cu" "F.Mask" "F.Paste")
			(net "GND")
		)
		(pad "AF20" smd circle
			(at -4.750054 0.94996)
			(size 0.4572 0.4572)
			(layers "F.Cu" "F.Mask" "F.Paste")
			(net "P0V8_PEX2")
		)
		(pad "AF21" smd circle
			(at -3.800094 0.94996)
			(size 0.4572 0.4572)
			(layers "F.Cu" "F.Mask" "F.Paste")
			(net "GND")
		)
		(pad "AF22" smd circle
			(at -2.84988 0.94996)
			(size 0.4572 0.4572)
			(layers "F.Cu" "F.Mask" "F.Paste")
			(net "P0V8_PEX2")
		)
		(pad "AF23" smd circle
			(at -1.89992 0.94996)
			(size 0.4572 0.4572)
			(layers "F.Cu" "F.Mask" "F.Paste")
			(net "GND")
		)
		(pad "AF24" smd circle
			(at -0.94996 0.94996)
			(size 0.4572 0.4572)
			(layers "F.Cu" "F.Mask" "F.Paste")
			(net "P0V8_PEX2")
		)
		(pad "AF25" smd circle
			(at 0 0.94996)
			(size 0.4572 0.4572)
			(layers "F.Cu" "F.Mask" "F.Paste")
			(net "GND")
		)
		(pad "AF26" smd circle
			(at 0.94996 0.94996)
			(size 0.4572 0.4572)
			(layers "F.Cu" "F.Mask" "F.Paste")
			(net "P0V8_PEX2")
		)
		(pad "AF27" smd circle
			(at 1.89992 0.94996)
			(size 0.4572 0.4572)
			(layers "F.Cu" "F.Mask" "F.Paste")
			(net "GND")
		)
		(pad "AF28" smd circle
			(at 2.84988 0.94996)
			(size 0.4572 0.4572)
			(layers "F.Cu" "F.Mask" "F.Paste")
			(net "P0V8_PEX2")
		)
		(pad "AF29" smd circle
			(at 3.800094 0.94996)
			(size 0.4572 0.4572)
			(layers "F.Cu" "F.Mask" "F.Paste")
			(net "GND")
		)
		(pad "AF30" smd circle
			(at 4.750054 0.94996)
			(size 0.4572 0.4572)
			(layers "F.Cu" "F.Mask" "F.Paste")
			(net "P0V8_PEX2")
		)
		(pad "AF31" smd circle
			(at 5.700014 0.94996)
			(size 0.4572 0.4572)
			(layers "F.Cu" "F.Mask" "F.Paste")
			(net "GND")
		)
		(pad "AF32" smd circle
			(at 6.649974 0.94996)
			(size 0.4572 0.4572)
			(layers "F.Cu" "F.Mask" "F.Paste")
			(net "P0V8_SERDES_VDDA_PEX2")
		)
		(pad "AF33" smd circle
			(at 7.599934 0.94996)
			(size 0.4572 0.4572)
			(layers "F.Cu" "F.Mask" "F.Paste")
			(net "P0V8_SERDES_VDDA_PEX2")
		)
		(pad "AF34" smd circle
			(at 8.549894 0.94996)
			(size 0.4572 0.4572)
			(layers "F.Cu" "F.Mask" "F.Paste")
			(net "P0V8_SERDES_VDDA_PEX2")
		)
		(pad "AF35" smd circle
			(at 9.500108 0.94996)
			(size 0.4572 0.4572)
			(layers "F.Cu" "F.Mask" "F.Paste")
			(net "GND")
		)
		(pad "AF36" smd circle
			(at 10.450068 0.94996)
			(size 0.4572 0.4572)
			(layers "F.Cu" "F.Mask" "F.Paste")
			(net "P1V25_PEX2")
		)
		(pad "AF37" smd circle
			(at 11.400028 0.94996)
			(size 0.4572 0.4572)
			(layers "F.Cu" "F.Mask" "F.Paste")
			(net "GND")
		)
		(pad "AF38" smd circle
			(at 12.349988 0.94996)
			(size 0.4572 0.4572)
			(layers "F.Cu" "F.Mask" "F.Paste")
			(net "P1V25_SERDES_VDDPLL_PEX2")
		)
		(pad "AF39" smd circle
			(at 13.299948 0.94996)
			(size 0.4572 0.4572)
			(layers "F.Cu" "F.Mask" "F.Paste")
			(net "GND")
		)
		(pad "AF40" smd circle
			(at 14.249908 0.94996)
			(size 0.4572 0.4572)
			(layers "F.Cu" "F.Mask" "F.Paste")
			(net "GND")
		)
		(pad "AF41" smd circle
			(at 15.200122 0.94996)
			(size 0.4572 0.4572)
			(layers "F.Cu" "F.Mask" "F.Paste")
			(net "Net_1675")
		)
		(pad "AF42" smd circle
			(at 16.150082 0.94996)
			(size 0.4572 0.4572)
			(layers "F.Cu" "F.Mask" "F.Paste")
			(net "Net_1667")
		)
		(pad "AF43" smd circle
			(at 17.100042 0.94996)
			(size 0.4572 0.4572)
			(layers "F.Cu" "F.Mask" "F.Paste")
			(net "GND")
		)
		(pad "AF44" smd circle
			(at 18.050002 0.94996)
			(size 0.4572 0.4572)
			(layers "F.Cu" "F.Mask" "F.Paste")
			(net "GND")
		)
		(pad "AF45" smd circle
			(at 18.999962 0.94996)
			(size 0.4572 0.4572)
			(layers "F.Cu" "F.Mask" "F.Paste")
			(net "GND")
		)
		(pad "AF46" smd circle
			(at 19.949922 0.94996)
			(size 0.4572 0.4572)
			(layers "F.Cu" "F.Mask" "F.Paste")
			(net "GND")
		)
		(pad "AF47" smd circle
			(at 20.899882 0.94996)
			(size 0.4572 0.4572)
			(layers "F.Cu" "F.Mask" "F.Paste")
			(net "GND")
		)
		(pad "AF48" smd circle
			(at 21.850096 0.94996)
			(size 0.4572 0.4572)
			(layers "F.Cu" "F.Mask" "F.Paste")
			(net "Net_1569")
		)
		(pad "AF49" smd circle
			(at 22.800056 0.94996)
			(size 0.4572 0.4572)
			(layers "F.Cu" "F.Mask" "F.Paste")
			(net "Net_1548")
		)
		(pad "AG1" smd circle
			(at -22.800056 1.89992)
			(size 0.4572 0.4572)
			(layers "F.Cu" "F.Mask" "F.Paste")
			(net "Net_5316")
		)
		(pad "AG2" smd circle
			(at -21.850096 1.89992)
			(size 0.4572 0.4572)
			(layers "F.Cu" "F.Mask" "F.Paste")
			(net "Net_5317")
		)
		(pad "AG3" smd circle
			(at -20.899882 1.89992)
			(size 0.4572 0.4572)
			(layers "F.Cu" "F.Mask" "F.Paste")
			(net "GND")
		)
		(pad "AG4" smd circle
			(at -19.949922 1.89992)
			(size 0.4572 0.4572)
			(layers "F.Cu" "F.Mask" "F.Paste")
			(net "GND")
		)
		(pad "AG5" smd circle
			(at -18.999962 1.89992)
			(size 0.4572 0.4572)
			(layers "F.Cu" "F.Mask" "F.Paste")
			(net "GND")
		)
		(pad "AG6" smd circle
			(at -18.050002 1.89992)
			(size 0.4572 0.4572)
			(layers "F.Cu" "F.Mask" "F.Paste")
			(net "GND")
		)
		(pad "AG7" smd circle
			(at -17.100042 1.89992)
			(size 0.4572 0.4572)
			(layers "F.Cu" "F.Mask" "F.Paste")
			(net "SPI_PEX2_RST_N")
		)
		(pad "AG8" smd circle
			(at -16.150082 1.89992)
			(size 0.4572 0.4572)
			(layers "F.Cu" "F.Mask" "F.Paste")
			(net "SPI_PEX2_SDIO2")
		)
		(pad "AG9" smd circle
			(at -15.200122 1.89992)
			(size 0.4572 0.4572)
			(layers "F.Cu" "F.Mask" "F.Paste")
			(net "GND")
		)
		(pad "AG10" smd circle
			(at -14.249908 1.89992)
			(size 0.4572 0.4572)
			(layers "F.Cu" "F.Mask" "F.Paste")
			(net "GND")
		)
		(pad "AG11" smd circle
			(at -13.299948 1.89992)
			(size 0.4572 0.4572)
			(layers "F.Cu" "F.Mask" "F.Paste")
			(net "GND")
		)
		(pad "AG12" smd circle
			(at -12.349988 1.89992)
			(size 0.4572 0.4572)
			(layers "F.Cu" "F.Mask" "F.Paste")
			(net "GND")
		)
		(pad "AG13" smd circle
			(at -11.400028 1.89992)
			(size 0.4572 0.4572)
			(layers "F.Cu" "F.Mask" "F.Paste")
			(net "PCEPLL5_VDDA18_PEX2")
		)
		(pad "AG14" smd circle
			(at -10.450068 1.89992)
			(size 0.4572 0.4572)
			(layers "F.Cu" "F.Mask" "F.Paste")
			(net "GND")
		)
	)
)
